# T6G (Grand Teton) — schematic netlist excerpt (pin names and nets, part order shuffled) for the footprints in the layout excerpt that follows; sources: Cadence DE-HDL packaged netlist, KiCad conversion of 04192023_DAF0TMB3IC0_F0TG_MB_C_brd_V02_OCP.brd

PC382_2  Q_CAP  22UF 16V 20% X6S  pkg C0805  page 218 : A = SW_P12V_AUX_PVDDCR_CPU1_P1_FLT ; B = GND
PC499_2  Q_CAP  22UF 4V 20% X6S  pkg C0805  page 194 : A = PVDDCR_CPU0_P0 ; B = GND
PR60  Q_RES  0 5% CHIP  pkg 0402LF  page 27 : A = SVID_PVDDCR_CPU1_P0_SVD_R ; B = SVID_PVDDCR_CPU1_P0_SVD

(kicad_pcb
	(version 20260206)
	(generator "pcbnew")
	(generator_version "10.0")
	(general
		(thickness 1.6)
		(legacy_teardrops no)
	)
	(paper "A4")
	(title_block
		(title "04192023_DAF0TMB3IC0_F0TG_MB_C_brd_V02_OCP.brd")
		(comment 1 "Grand Teton / footprints 7759-7761 of 8354")
	)
	(layers
		(0 "F.Cu" signal "TOP")
		(4 "In1.Cu" signal "GND")
		(6 "In2.Cu" signal "IN1")
		(8 "In3.Cu" signal "GND1")
		(10 "In4.Cu" signal "IN2")
		(12 "In5.Cu" signal "GND2")
		(14 "In6.Cu" signal "IN3")
		(16 "In7.Cu" signal "GND3")
		(18 "In8.Cu" signal "VCC")
		(20 "In9.Cu" signal "VCC1")
		(22 "In10.Cu" signal "GND4")
		(24 "In11.Cu" signal "IN4")
		(26 "In12.Cu" signal "GND5")
		(28 "In13.Cu" signal "IN5")
		(30 "In14.Cu" signal "GND6")
		(32 "In15.Cu" signal "IN6")
		(34 "In16.Cu" signal "GND7")
		(2 "B.Cu" signal "BOTTOM")
		(9 "F.Adhes" user "F.Adhesive")
		(11 "B.Adhes" user "B.Adhesive")
		(13 "F.Paste" user "Package Geometry/Pastemask Top")
		(15 "B.Paste" user "Package Geometry/Pastemask Bottom")
		(5 "F.SilkS" user "Ref Des/Silkscreen Top")
		(7 "B.SilkS" user "Ref Des/Silkscreen Bottom")
		(1 "F.Mask" user "Board Geometry/Soldermask Top")
		(3 "B.Mask" user "Board Geometry/Soldermask Bottom")
		(17 "Dwgs.User" user "User.Drawings")
		(19 "Cmts.User" user "User.Comments")
		(21 "Eco1.User" user "User.Eco1")
		(23 "Eco2.User" user "User.Eco2")
		(25 "Edge.Cuts" user "Board Geometry/Outline")
		(27 "Margin" user)
		(31 "F.CrtYd" user "Package Geometry/Place Bound Top")
		(29 "B.CrtYd" user "Package Geometry/Place Bound Bottom")
		(35 "F.Fab" user "Ref Des/Assembly Top")
		(33 "B.Fab" user "Ref Des/Assembly Bottom")
	)
	(footprint ""
		(layer "B.Cu")
		(at 79.886302 -335.060798 90)
		(property "Reference" "PC382_2"
			(at 0 0 90)
			(layer "B.SilkS")
			(hide yes)
			(effects
				(font
					(size 1.27 1.27)
				)
				(justify mirror)
			)
		)
		(property "Value" ""
			(at 0 0 90)
			(layer "B.Fab")
			(effects
				(font
					(size 1.27 1.27)
				)
				(justify mirror)
			)
		)
		(duplicate_pad_numbers_are_jumpers no)
		(fp_line
			(start 1.524 -0.762)
			(end -1.524 -0.762)
			(stroke
				(width 0.1524)
				(type default)
			)
			(layer "B.SilkS")
		)
		(fp_line
			(start -1.524 -0.762)
			(end -1.524 0.762)
			(stroke
				(width 0.1524)
				(type default)
			)
			(layer "B.SilkS")
		)
		(fp_line
			(start 1.524 0.762)
			(end 1.524 -0.762)
			(stroke
				(width 0.1524)
				(type default)
			)
			(layer "B.SilkS")
		)
		(fp_line
			(start -1.524 0.762)
			(end 1.524 0.762)
			(stroke
				(width 0.1524)
				(type default)
			)
			(layer "B.SilkS")
		)
		(fp_line
			(start 1.1049 -0.724916)
			(end 1.1049 0.724916)
			(stroke
				(width 0.1)
				(type default)
			)
			(layer "B.Fab")
		)
		(fp_line
			(start -1.1049 -0.724916)
			(end 1.1049 -0.724916)
			(stroke
				(width 0.1)
				(type default)
			)
			(layer "B.Fab")
		)
		(fp_line
			(start 1.1049 0.724916)
			(end -1.1049 0.724916)
			(stroke
				(width 0.1)
				(type default)
			)
			(layer "B.Fab")
		)
		(fp_line
			(start -1.1049 0.724916)
			(end -1.1049 -0.724916)
			(stroke
				(width 0.1)
				(type default)
			)
			(layer "B.Fab")
		)
		(pad "1" smd rect
			(at 0.889 0 90)
			(size 1.016 1.27)
			(layers "B.Cu" "B.Mask" "B.Paste")
			(net "SW_P12V_AUX_PVDDCR_CPU1_P1_FLT")
		)
		(pad "2" smd rect
			(at -0.889 0 90)
			(size 1.016 1.27)
			(layers "B.Cu" "B.Mask" "B.Paste")
			(net "GND")
		)
	)
	(footprint ""
		(layer "B.Cu")
		(at 339.148928 -312.053986)
		(property "Reference" "PR60"
			(at 0 0 0)
			(layer "B.SilkS")
			(hide yes)
			(effects
				(font
					(size 1.27 1.27)
				)
				(justify mirror)
			)
		)
		(property "Value" ""
			(at 0 0 0)
			(layer "B.Fab")
			(effects
				(font
					(size 1.27 1.27)
				)
				(justify mirror)
			)
		)
		(duplicate_pad_numbers_are_jumpers no)
		(fp_line
			(start -0.7874 -0.4064)
			(end -0.7874 0.4064)
			(stroke
				(width 0.1524)
				(type default)
			)
			(layer "B.SilkS")
		)
		(fp_line
			(start -0.7874 0.4064)
			(end 0.7874 0.4064)
			(stroke
				(width 0.1524)
				(type default)
			)
			(layer "B.SilkS")
		)
		(fp_line
			(start 0.7874 -0.4064)
			(end -0.7874 -0.4064)
			(stroke
				(width 0.1524)
				(type default)
			)
			(layer "B.SilkS")
		)
		(fp_line
			(start 0.7874 0.4064)
			(end 0.7874 -0.4064)
			(stroke
				(width 0.1524)
				(type default)
			)
			(layer "B.SilkS")
		)
		(fp_line
			(start -0.67945 -0.3048)
			(end -0.67945 0.3048)
			(stroke
				(width 0.1)
				(type default)
			)
			(layer "B.Fab")
		)
		(fp_line
			(start -0.67945 0.3048)
			(end -0.120396 0.3048)
			(stroke
				(width 0.1)
				(type default)
			)
			(layer "B.Fab")
		)
		(fp_line
			(start -0.12065 -0.3048)
			(end -0.67945 -0.3048)
			(stroke
				(width 0.1)
				(type default)
			)
			(layer "B.Fab")
		)
		(fp_line
			(start -0.12065 -0.2794)
			(end -0.12065 -0.3048)
			(stroke
				(width 0.1)
				(type default)
			)
			(layer "B.Fab")
		)
		(fp_line
			(start -0.120396 0.2794)
			(end 0.12065 0.2794)
			(stroke
				(width 0.1)
				(type default)
			)
			(layer "B.Fab")
		)
		(fp_line
			(start -0.120396 0.3048)
			(end -0.120396 0.2794)
			(stroke
				(width 0.1)
				(type default)
			)
			(layer "B.Fab")
		)
		(fp_line
			(start 0.12065 -0.305054)
			(end 0.12065 -0.2794)
			(stroke
				(width 0.1)
				(type default)
			)
			(layer "B.Fab")
		)
		(fp_line
			(start 0.12065 -0.2794)
			(end -0.12065 -0.2794)
			(stroke
				(width 0.1)
				(type default)
			)
			(layer "B.Fab")
		)
		(fp_line
			(start 0.12065 0.2794)
			(end 0.12065 0.3048)
			(stroke
				(width 0.1)
				(type default)
			)
			(layer "B.Fab")
		)
		(fp_line
			(start 0.12065 0.3048)
			(end 0.67945 0.3048)
			(stroke
				(width 0.1)
				(type default)
			)
			(layer "B.Fab")
		)
		(fp_line
			(start 0.67945 -0.305054)
			(end 0.12065 -0.305054)
			(stroke
				(width 0.1)
				(type default)
			)
			(layer "B.Fab")
		)
		(fp_line
			(start 0.67945 0.3048)
			(end 0.67945 -0.305054)
			(stroke
				(width 0.1)
				(type default)
			)
			(layer "B.Fab")
		)
		(pad "1" smd circle
			(at 0.40005 0 180)
			(size 0 0)
			(layers "B.Cu" "B.Mask" "B.Paste")
			(net "SVID_PVDDCR_CPU1_P0_SVD_R")
		)
		(pad "2" smd circle
			(at -0.40005 0 180)
			(size 0 0)
			(layers "B.Cu" "B.Mask" "B.Paste")
			(net "SVID_PVDDCR_CPU1_P0_SVD")
		)
	)
	(footprint ""
		(layer "B.Cu")
		(at 361.54106 -186.225942 90)
		(property "Reference" "PC499_2"
			(at 0 0 90)
			(layer "B.SilkS")
			(hide yes)
			(effects
				(font
					(size 1.27 1.27)
				)
				(justify mirror)
			)
		)
		(property "Value" ""
			(at 0 0 90)
			(layer "B.Fab")
			(effects
				(font
					(size 1.27 1.27)
				)
				(justify mirror)
			)
		)
		(duplicate_pad_numbers_are_jumpers no)
		(fp_line
			(start 1.524 -0.762)
			(end -1.524 -0.762)
			(stroke
				(width 0.1524)
				(type default)
			)
			(layer "B.SilkS")
		)
		(fp_line
			(start -1.524 -0.762)
			(end -1.524 0.762)
			(stroke
				(width 0.1524)
				(type default)
			)
			(layer "B.SilkS")
		)
		(fp_line
			(start 1.524 0.762)
			(end 1.524 -0.762)
			(stroke
				(width 0.1524)
				(type default)
			)
			(layer "B.SilkS")
		)
		(fp_line
			(start -1.524 0.762)
			(end 1.524 0.762)
			(stroke
				(width 0.1524)
				(type default)
			)
			(layer "B.SilkS")
		)
		(fp_line
			(start 1.1049 -0.724916)
			(end 1.1049 0.724916)
			(stroke
				(width 0.1)
				(type default)
			)
			(layer "B.Fab")
		)
		(fp_line
			(start -1.1049 -0.724916)
			(end 1.1049 -0.724916)
			(stroke
				(width 0.1)
				(type default)
			)
			(layer "B.Fab")
		)
		(fp_line
			(start 1.1049 0.724916)
			(end -1.1049 0.724916)
			(stroke
				(width 0.1)
				(type default)
			)
			(layer "B.Fab")
		)
		(fp_line
			(start -1.1049 0.724916)
			(end -1.1049 -0.724916)
			(stroke
				(width 0.1)
				(type default)
			)
			(layer "B.Fab")
		)
		(pad "1" smd rect
			(at 0.889 0 90)
			(size 1.016 1.27)
			(layers "B.Cu" "B.Mask" "B.Paste")
			(net "PVDDCR_CPU0_P0")
		)
		(pad "2" smd rect
			(at -0.889 0 90)
			(size 1.016 1.27)
			(layers "B.Cu" "B.Mask" "B.Paste")
			(net "GND")
		)
	)
)
